(kicad_pcb
	(version 20260206)
	(generator "pcbnew")
	(generator_version "10.0")
	(general
		(thickness 1.6)
		(legacy_teardrops no)
	)
	(paper "A4")
	(title_block
		(title "Wiwynn_Tioga_Pass_MB.brd")
		(comment 1 "Tioga Pass / footprint 190 of 4770 (U2D1), pads 1863-1964 of 3647")
	)
	(layers
		(0 "F.Cu" signal "TOP")
		(4 "In1.Cu" signal "L2GND")
		(6 "In2.Cu" signal "L3")
		(8 "In3.Cu" signal "L4GND")
		(10 "In4.Cu" signal "L5")
		(12 "In5.Cu" signal "L6GND")
		(14 "In6.Cu" signal "L7VCC")
		(16 "In7.Cu" signal "L8VCC")
		(18 "In8.Cu" signal "L9GND")
		(20 "In9.Cu" signal "L10")
		(22 "In10.Cu" signal "L11GND")
		(24 "In11.Cu" signal "L12")
		(26 "In12.Cu" signal "L13GND")
		(2 "B.Cu" signal "BOTTOM")
		(9 "F.Adhes" user "F.Adhesive")
		(11 "B.Adhes" user "B.Adhesive")
		(13 "F.Paste" user "Package Geometry/Pastemask Top")
		(15 "B.Paste" user "Package Geometry/Pastemask Bottom")
		(5 "F.SilkS" user "Ref Des/Silkscreen Top")
		(7 "B.SilkS" user "Ref Des/Silkscreen Bottom")
		(1 "F.Mask" user "Board Geometry/Soldermask Top")
		(3 "B.Mask" user "Board Geometry/Soldermask Bottom")
		(17 "Dwgs.User" user "User.Drawings")
		(19 "Cmts.User" user "User.Comments")
		(21 "Eco1.User" user "User.Eco1")
		(23 "Eco2.User" user "User.Eco2")
		(25 "Edge.Cuts" user "Board Geometry/Outline")
		(27 "Margin" user)
		(31 "F.CrtYd" user "Package Geometry/Place Bound Top")
		(29 "B.CrtYd" user "Package Geometry/Place Bound Bottom")
		(35 "F.Fab" user "Ref Des/Assembly Top")
		(33 "B.Fab" user "Ref Des/Assembly Bottom")
	)
	(footprint ""
		(layer "F.Cu")
		(at 104.99979 -76.550012 180)
		(property "Reference" "U2D1"
			(at 25.19299 30.484318 0)
			(unlocked yes)
			(layer "F.SilkS")
			(effects
				(font
					(size 0.7874 0.5842)
					(thickness 0.1524)
				)
			)
		)
		(property "Value" ""
			(at 0 0 180)
			(layer "F.Fab")
			(effects
				(font
					(size 1.27 1.27)
				)
			)
		)
		(duplicate_pad_numbers_are_jumpers no)
		(pad "CY1" smd custom
			(at -37.250624 14.025372 90)
			(size 0.10795 0.10795)
			(layers "F.Cu" "F.Mask" "F.Paste")
			(net "GND")
			(options
				(clearance outline)
				(anchor circle)
			)
			(primitives
				(gr_poly
					(pts
						(arc
							(start 0.2159 -0.0381)
							(mid 0 -0.254)
							(end -0.2159 -0.0381)
						)
						(arc
							(start -0.2159 0.0381)
							(mid 0 0.254)
							(end 0.2159 0.0381)
						)
					)
					(width 0)
					(fill yes)
				)
			)
		)
		(pad "CY3" smd circle
			(at -35.533584 14.025372)
			(size 0.4318 0.4318)
			(layers "F.Cu" "F.Mask" "F.Paste")
			(net "TP_P3E_CPU1_PE2_RSR_TXN<0>")
		)
		(pad "CY5" smd circle
			(at -33.816544 14.025372)
			(size 0.4318 0.4318)
			(layers "F.Cu" "F.Mask" "F.Paste")
			(net "P3E_CPU1_PE3_MP_TXN<15>")
		)
		(pad "CY7" smd circle
			(at -32.099504 14.025372)
			(size 0.4318 0.4318)
			(layers "F.Cu" "F.Mask" "F.Paste")
			(net "TP_P3E_CPU1_PE1_MP_RXP<1>")
		)
		(pad "CY9" smd circle
			(at -30.382464 14.025372)
			(size 0.4318 0.4318)
			(layers "F.Cu" "F.Mask" "F.Paste")
			(net "GND")
		)
		(pad "CY11" smd circle
			(at -28.665424 14.025372)
			(size 0.4318 0.4318)
			(layers "F.Cu" "F.Mask" "F.Paste")
			(net "P3E_CPU1_PE3_MP_RXN<14>")
		)
		(pad "CY13" smd circle
			(at -26.948384 14.025372)
			(size 0.4318 0.4318)
			(layers "F.Cu" "F.Mask" "F.Paste")
			(net "GND")
		)
		(pad "CY15" smd circle
			(at -25.231598 14.025372)
			(size 0.4318 0.4318)
			(layers "F.Cu" "F.Mask" "F.Paste")
			(net "GND")
		)
		(pad "CY17" smd circle
			(at -23.514558 14.025372)
			(size 0.4318 0.4318)
			(layers "F.Cu" "F.Mask" "F.Paste")
			(net "PVCCIO_CPU1")
		)
		(pad "CY19" smd circle
			(at -21.797518 14.025372)
			(size 0.4318 0.4318)
			(layers "F.Cu" "F.Mask" "F.Paste")
			(net "GND")
		)
		(pad "CY21" smd circle
			(at -20.080478 14.025372)
			(size 0.4318 0.4318)
			(layers "F.Cu" "F.Mask" "F.Paste")
			(net "GND")
		)
		(pad "CY23" smd circle
			(at -18.363438 14.025372)
			(size 0.4318 0.4318)
			(layers "F.Cu" "F.Mask" "F.Paste")
			(net "TP_CPU1_RSVD_59")
		)
		(pad "CY25" smd circle
			(at -16.646398 14.025372)
			(size 0.4318 0.4318)
			(layers "F.Cu" "F.Mask" "F.Paste")
			(net "PVCCMCP_CPU1")
		)
		(pad "CY27" smd circle
			(at -14.929612 14.025372)
			(size 0.4318 0.4318)
			(layers "F.Cu" "F.Mask" "F.Paste")
			(net "M_M_DQ<58>")
		)
		(pad "CY29" smd circle
			(at -13.212572 14.025372)
			(size 0.4318 0.4318)
			(layers "F.Cu" "F.Mask" "F.Paste")
			(net "M_M_DQS_DN<16>")
		)
		(pad "CY31" smd circle
			(at -11.495532 14.025372)
			(size 0.4318 0.4318)
			(layers "F.Cu" "F.Mask" "F.Paste")
			(net "M_M_DQ<60>")
		)
		(pad "CY33" smd circle
			(at -9.778492 14.025372)
			(size 0.4318 0.4318)
			(layers "F.Cu" "F.Mask" "F.Paste")
			(net "M_M_DQ<50>")
		)
		(pad "CY35" smd circle
			(at -8.061452 14.025372)
			(size 0.4318 0.4318)
			(layers "F.Cu" "F.Mask" "F.Paste")
			(net "M_M_DQS_DN<15>")
		)
		(pad "CY37" smd circle
			(at -6.344412 14.025372)
			(size 0.4318 0.4318)
			(layers "F.Cu" "F.Mask" "F.Paste")
			(net "M_M_DQ<52>")
		)
		(pad "CY39" smd circle
			(at -4.627626 14.025372)
			(size 0.4318 0.4318)
			(layers "F.Cu" "F.Mask" "F.Paste")
			(net "TP_CPU1_RSVD_57")
		)
		(pad "CY41" smd circle
			(at -2.910586 14.025372)
			(size 0.4318 0.4318)
			(layers "F.Cu" "F.Mask" "F.Paste")
			(net "GND")
		)
		(pad "CY45" smd circle
			(at 2.052066 12.225274)
			(size 0.508 0.508)
			(layers "F.Cu" "F.Mask" "F.Paste")
			(net "GND")
		)
		(pad "CY47" smd circle
			(at 3.769106 12.225274)
			(size 0.4318 0.4318)
			(layers "F.Cu" "F.Mask" "F.Paste")
			(net "PVCCIN_CPU1")
		)
		(pad "CY49" smd circle
			(at 5.485892 12.225274)
			(size 0.4318 0.4318)
			(layers "F.Cu" "F.Mask" "F.Paste")
			(net "PVCCIN_CPU1")
		)
		(pad "CY51" smd circle
			(at 7.202932 12.225274)
			(size 0.4318 0.4318)
			(layers "F.Cu" "F.Mask" "F.Paste")
			(net "GND")
		)
		(pad "CY53" smd circle
			(at 8.919972 12.225274)
			(size 0.4318 0.4318)
			(layers "F.Cu" "F.Mask" "F.Paste")
			(net "TP_CPU1_RSVD_56")
		)
		(pad "CY55" smd circle
			(at 10.637012 12.225274)
			(size 0.4318 0.4318)
			(layers "F.Cu" "F.Mask" "F.Paste")
			(net "P3V3_STBY")
		)
		(pad "CY57" smd circle
			(at 12.354052 12.225274)
			(size 0.4318 0.4318)
			(layers "F.Cu" "F.Mask" "F.Paste")
			(net "TP_CPU1_RSVD_55")
		)
		(pad "CY59" smd circle
			(at 14.071092 12.225274)
			(size 0.4318 0.4318)
			(layers "F.Cu" "F.Mask" "F.Paste")
			(net "GND")
		)
		(pad "CY61" smd circle
			(at 15.787878 12.225274)
			(size 0.4318 0.4318)
			(layers "F.Cu" "F.Mask" "F.Paste")
			(net "GND")
		)
		(pad "CY63" smd circle
			(at 17.504918 12.225274)
			(size 0.4318 0.4318)
			(layers "F.Cu" "F.Mask" "F.Paste")
			(net "TP_CPU1_RSVD_54")
		)
		(pad "CY65" smd circle
			(at 19.221958 12.225274)
			(size 0.4318 0.4318)
			(layers "F.Cu" "F.Mask" "F.Paste")
			(net "GND")
		)
		(pad "CY67" smd circle
			(at 20.938998 12.225274)
			(size 0.4318 0.4318)
			(layers "F.Cu" "F.Mask" "F.Paste")
			(net "M_K_DQS_DP<17>")
		)
		(pad "CY69" smd circle
			(at 22.656038 12.225274)
			(size 0.4318 0.4318)
			(layers "F.Cu" "F.Mask" "F.Paste")
			(net "GND")
		)
		(pad "CY71" smd circle
			(at 24.373078 12.225274)
			(size 0.4318 0.4318)
			(layers "F.Cu" "F.Mask" "F.Paste")
			(net "FM_CPU1_PROC_ID0")
		)
		(pad "CY73" smd circle
			(at 26.090118 12.225274)
			(size 0.4318 0.4318)
			(layers "F.Cu" "F.Mask" "F.Paste")
			(net "TP_CPU1_RSVD_53")
		)
		(pad "CY75" smd circle
			(at 27.806904 12.225274)
			(size 0.4318 0.4318)
			(layers "F.Cu" "F.Mask" "F.Paste")
			(net "GND")
		)
		(pad "CY77" smd circle
			(at 29.523944 12.225274)
			(size 0.4318 0.4318)
			(layers "F.Cu" "F.Mask" "F.Paste")
			(net "GND")
		)
		(pad "CY79" smd circle
			(at 31.240984 12.225274)
			(size 0.4318 0.4318)
			(layers "F.Cu" "F.Mask" "F.Paste")
			(net "M_L_DQ<12>")
		)
		(pad "CY81" smd circle
			(at 32.958024 12.225274)
			(size 0.4318 0.4318)
			(layers "F.Cu" "F.Mask" "F.Paste")
			(net "M_L_DQ<9>")
		)
		(pad "CY83" smd circle
			(at 34.675064 12.225274)
			(size 0.4318 0.4318)
			(layers "F.Cu" "F.Mask" "F.Paste")
			(net "GND")
		)
		(pad "CY85" smd circle
			(at 36.392104 12.225274)
			(size 0.4318 0.4318)
			(layers "F.Cu" "F.Mask" "F.Paste")
			(net "GND")
		)
		(pad "D3" smd custom
			(at -35.533584 -23.617174 45)
			(size 0.10795 0.10795)
			(layers "F.Cu" "F.Mask" "F.Paste")
			(net "GND")
			(options
				(clearance outline)
				(anchor circle)
			)
			(primitives
				(gr_poly
					(pts
						(arc
							(start 0.2159 -0.0381)
							(mid 0 -0.254)
							(end -0.2159 -0.0381)
						)
						(arc
							(start -0.2159 0.0381)
							(mid 0 0.254)
							(end 0.2159 0.0381)
						)
					)
					(width 0)
					(fill yes)
				)
			)
		)
		(pad "D5" smd custom
			(at -33.816544 -23.617174 90)
			(size 0.10795 0.10795)
			(layers "F.Cu" "F.Mask" "F.Paste")
			(net "TP_CPU1_RSVD_287")
			(options
				(clearance outline)
				(anchor circle)
			)
			(primitives
				(gr_poly
					(pts
						(arc
							(start 0.2159 -0.0381)
							(mid 0 -0.254)
							(end -0.2159 -0.0381)
						)
						(arc
							(start -0.2159 0.0381)
							(mid 0 0.254)
							(end 0.2159 0.0381)
						)
					)
					(width 0)
					(fill yes)
				)
			)
		)
		(pad "D7" smd circle
			(at -32.099504 -23.617174)
			(size 0.4318 0.4318)
			(layers "F.Cu" "F.Mask" "F.Paste")
			(net "PVCCIO_CPU1")
		)
		(pad "D9" smd circle
			(at -30.382464 -23.617174)
			(size 0.4318 0.4318)
			(layers "F.Cu" "F.Mask" "F.Paste")
			(net "UPI_CPU1_CPU0_P1P1_DP<7>")
		)
		(pad "D11" smd circle
			(at -28.665424 -23.617174)
			(size 0.4318 0.4318)
			(layers "F.Cu" "F.Mask" "F.Paste")
			(net "GND")
		)
		(pad "D13" smd circle
			(at -26.948384 -23.617174)
			(size 0.4318 0.4318)
			(layers "F.Cu" "F.Mask" "F.Paste")
			(net "GND")
		)
		(pad "D15" smd circle
			(at -25.231598 -23.617174)
			(size 0.4318 0.4318)
			(layers "F.Cu" "F.Mask" "F.Paste")
			(net "UPI_CPU1_CPU0_P1P1_DN<12>")
		)
		(pad "D17" smd circle
			(at -23.514558 -23.617174)
			(size 0.4318 0.4318)
			(layers "F.Cu" "F.Mask" "F.Paste")
			(net "TP_CPU1_RSVD_286")
		)
		(pad "D25" smd circle
			(at -16.646398 -23.617174)
			(size 0.4318 0.4318)
			(layers "F.Cu" "F.Mask" "F.Paste")
			(net "GND")
		)
		(pad "D27" smd circle
			(at -14.929612 -23.617174)
			(size 0.4318 0.4318)
			(layers "F.Cu" "F.Mask" "F.Paste")
			(net "GND")
		)
		(pad "D29" smd circle
			(at -13.212572 -23.617174)
			(size 0.4318 0.4318)
			(layers "F.Cu" "F.Mask" "F.Paste")
			(net "GND")
		)
		(pad "D31" smd circle
			(at -11.495532 -23.617174)
			(size 0.4318 0.4318)
			(layers "F.Cu" "F.Mask" "F.Paste")
			(net "GND")
		)
		(pad "D33" smd circle
			(at -9.778492 -23.617174)
			(size 0.4318 0.4318)
			(layers "F.Cu" "F.Mask" "F.Paste")
			(net "GND")
		)
		(pad "D35" smd circle
			(at -8.061452 -23.617174)
			(size 0.4318 0.4318)
			(layers "F.Cu" "F.Mask" "F.Paste")
			(net "GND")
		)
		(pad "D37" smd circle
			(at -6.344412 -23.617174)
			(size 0.4318 0.4318)
			(layers "F.Cu" "F.Mask" "F.Paste")
			(net "GND")
		)
		(pad "D39" smd circle
			(at -4.627626 -23.617174)
			(size 0.4318 0.4318)
			(layers "F.Cu" "F.Mask" "F.Paste")
			(net "GND")
		)
		(pad "D41" smd circle
			(at -2.910586 -23.617174)
			(size 0.4318 0.4318)
			(layers "F.Cu" "F.Mask" "F.Paste")
			(net "GND")
		)
		(pad "D43" smd circle
			(at -1.193546 -23.617174)
			(size 0.4318 0.4318)
			(layers "F.Cu" "F.Mask" "F.Paste")
			(net "GND")
		)
		(pad "D45" smd custom
			(at 2.052066 -25.417526 45)
			(size 0.10795 0.10795)
			(layers "F.Cu" "F.Mask" "F.Paste")
			(net "PVDDQ_GHJ")
			(options
				(clearance outline)
				(anchor circle)
			)
			(primitives
				(gr_poly
					(pts
						(arc
							(start 0.2159 -0.0381)
							(mid 0 -0.254)
							(end -0.2159 -0.0381)
						)
						(arc
							(start -0.2159 0.0381)
							(mid 0 0.254)
							(end 0.2159 0.0381)
						)
					)
					(width 0)
					(fill yes)
				)
			)
		)
		(pad "D47" smd circle
			(at 3.769106 -25.417526)
			(size 0.4318 0.4318)
			(layers "F.Cu" "F.Mask" "F.Paste")
			(net "M_G_CS_N<2>")
		)
		(pad "D49" smd circle
			(at 5.485892 -25.417526)
			(size 0.4318 0.4318)
			(layers "F.Cu" "F.Mask" "F.Paste")
			(net "M_G_CS_N<5>")
		)
		(pad "D51" smd circle
			(at 7.202932 -25.417526)
			(size 0.4318 0.4318)
			(layers "F.Cu" "F.Mask" "F.Paste")
			(net "M_G_MA<16>")
		)
		(pad "D53" smd circle
			(at 8.919972 -25.417526)
			(size 0.4318 0.4318)
			(layers "F.Cu" "F.Mask" "F.Paste")
			(net "M_G_PAR")
		)
		(pad "D55" smd circle
			(at 10.637012 -25.417526)
			(size 0.4318 0.4318)
			(layers "F.Cu" "F.Mask" "F.Paste")
			(net "M_G_CLK_DP<0>")
		)
		(pad "D57" smd circle
			(at 12.354052 -25.417526)
			(size 0.4318 0.4318)
			(layers "F.Cu" "F.Mask" "F.Paste")
			(net "M_G_MA<2>")
		)
		(pad "D59" smd circle
			(at 14.071092 -25.417526)
			(size 0.4318 0.4318)
			(layers "F.Cu" "F.Mask" "F.Paste")
			(net "M_G_MA<6>")
		)
		(pad "D61" smd circle
			(at 15.787878 -25.417526)
			(size 0.4318 0.4318)
			(layers "F.Cu" "F.Mask" "F.Paste")
			(net "M_G_BG<0>")
		)
		(pad "D63" smd circle
			(at 17.504918 -25.417526)
			(size 0.4318 0.4318)
			(layers "F.Cu" "F.Mask" "F.Paste")
			(net "M_G_CKE<3>")
		)
		(pad "D65" smd custom
			(at 19.221958 -25.417526)
			(size 0.10795 0.10795)
			(layers "F.Cu" "F.Mask" "F.Paste")
			(net "TP_CPU1_RSVD_285")
			(options
				(clearance outline)
				(anchor circle)
			)
			(primitives
				(gr_poly
					(pts
						(arc
							(start 0.2159 -0.0381)
							(mid 0 -0.254)
							(end -0.2159 -0.0381)
						)
						(arc
							(start -0.2159 0.0381)
							(mid 0 0.254)
							(end 0.2159 0.0381)
						)
					)
					(width 0)
					(fill yes)
				)
			)
		)
		(pad "D71" smd custom
			(at 24.373078 -25.417526)
			(size 0.10795 0.10795)
			(layers "F.Cu" "F.Mask" "F.Paste")
			(net "M_H_DQ<26>")
			(options
				(clearance outline)
				(anchor circle)
			)
			(primitives
				(gr_poly
					(pts
						(arc
							(start 0.2159 -0.0381)
							(mid 0 -0.254)
							(end -0.2159 -0.0381)
						)
						(arc
							(start -0.2159 0.0381)
							(mid 0 0.254)
							(end 0.2159 0.0381)
						)
					)
					(width 0)
					(fill yes)
				)
			)
		)
		(pad "D73" smd circle
			(at 26.090118 -25.417526)
			(size 0.4318 0.4318)
			(layers "F.Cu" "F.Mask" "F.Paste")
			(net "M_H_DQS_DP<12>")
		)
		(pad "D75" smd circle
			(at 27.806904 -25.417526)
			(size 0.4318 0.4318)
			(layers "F.Cu" "F.Mask" "F.Paste")
			(net "M_H_DQ<24>")
		)
		(pad "D77" smd circle
			(at 29.523944 -25.417526)
			(size 0.4318 0.4318)
			(layers "F.Cu" "F.Mask" "F.Paste")
			(net "GND")
		)
		(pad "D79" smd circle
			(at 31.240984 -25.417526)
			(size 0.4318 0.4318)
			(layers "F.Cu" "F.Mask" "F.Paste")
			(net "M_H_DQS_DN<11>")
		)
		(pad "D81" smd custom
			(at 32.958024 -25.417526 315)
			(size 0.10795 0.10795)
			(layers "F.Cu" "F.Mask" "F.Paste")
			(net "GND")
			(options
				(clearance outline)
				(anchor circle)
			)
			(primitives
				(gr_poly
					(pts
						(arc
							(start 0.2159 -0.0381)
							(mid 0 -0.254)
							(end -0.2159 -0.0381)
						)
						(arc
							(start -0.2159 0.0381)
							(mid 0 0.254)
							(end 0.2159 0.0381)
						)
					)
					(width 0)
					(fill yes)
				)
			)
		)
		(pad "D83" smd custom
			(at 34.675064 -25.417526 270)
			(size 0.10795 0.10795)
			(layers "F.Cu" "F.Mask" "F.Paste")
			(net "TP_CPU1_RSVD_284")
			(options
				(clearance outline)
				(anchor circle)
			)
			(primitives
				(gr_poly
					(pts
						(arc
							(start 0.2159 -0.0381)
							(mid 0 -0.254)
							(end -0.2159 -0.0381)
						)
						(arc
							(start -0.2159 0.0381)
							(mid 0 0.254)
							(end 0.2159 0.0381)
						)
					)
					(width 0)
					(fill yes)
				)
			)
		)
		(pad "DA2" smd circle
			(at -36.392104 14.520926)
			(size 0.4318 0.4318)
			(layers "F.Cu" "F.Mask" "F.Paste")
			(net "TP_P3E_CPU1_PE1_MP_TXN<0>")
		)
		(pad "DA4" smd circle
			(at -34.675064 14.520926)
			(size 0.4318 0.4318)
			(layers "F.Cu" "F.Mask" "F.Paste")
			(net "P3E_CPU1_PE3_MP_TXP<14>")
		)
		(pad "DA6" smd circle
			(at -32.958024 14.520926)
			(size 0.4318 0.4318)
			(layers "F.Cu" "F.Mask" "F.Paste")
			(net "GND")
		)
		(pad "DA8" smd circle
			(at -31.240984 14.520926)
			(size 0.4318 0.4318)
			(layers "F.Cu" "F.Mask" "F.Paste")
			(net "TP_P3E_CPU1_PE1_MP_RXN<1>")
		)
		(pad "DA10" smd circle
			(at -29.523944 14.520926)
			(size 0.4318 0.4318)
			(layers "F.Cu" "F.Mask" "F.Paste")
			(net "TP_P3E_CPU1_PE1_MP_RXP<3>")
		)
		(pad "DA12" smd circle
			(at -27.806904 14.520926)
			(size 0.4318 0.4318)
			(layers "F.Cu" "F.Mask" "F.Paste")
			(net "P3E_CPU1_PE3_MP_RXP<13>")
		)
		(pad "DA14" smd circle
			(at -26.090118 14.520926)
			(size 0.4318 0.4318)
			(layers "F.Cu" "F.Mask" "F.Paste")
			(net "PVCCIO_CPU1")
		)
		(pad "DA16" smd circle
			(at -24.373078 14.520926)
			(size 0.4318 0.4318)
			(layers "F.Cu" "F.Mask" "F.Paste")
			(net "TP_CPU1_UPI2_RSVD_DC16")
		)
		(pad "DA18" smd circle
			(at -22.656038 14.520926)
			(size 0.4318 0.4318)
			(layers "F.Cu" "F.Mask" "F.Paste")
			(net "GND")
		)
		(pad "DA20" smd circle
			(at -20.938998 14.520926)
			(size 0.4318 0.4318)
			(layers "F.Cu" "F.Mask" "F.Paste")
			(net "GND")
		)
		(pad "DA22" smd circle
			(at -19.221958 14.520926)
			(size 0.4318 0.4318)
			(layers "F.Cu" "F.Mask" "F.Paste")
			(net "GND")
		)
		(pad "DA24" smd circle
			(at -17.504918 14.520926)
			(size 0.4318 0.4318)
			(layers "F.Cu" "F.Mask" "F.Paste")
			(net "PVCCMCP_CPU1")
		)
		(pad "DA26" smd circle
			(at -15.787878 14.520926)
			(size 0.4318 0.4318)
			(layers "F.Cu" "F.Mask" "F.Paste")
			(net "GND")
		)
		(pad "DA28" smd circle
			(at -14.071092 14.520926)
			(size 0.4318 0.4318)
			(layers "F.Cu" "F.Mask" "F.Paste")
			(net "GND")
		)
		(pad "DA30" smd circle
			(at -12.354052 14.520926)
			(size 0.4318 0.4318)
			(layers "F.Cu" "F.Mask" "F.Paste")
			(net "GND")
		)
		(pad "DA32" smd circle
			(at -10.637012 14.520926)
			(size 0.4318 0.4318)
			(layers "F.Cu" "F.Mask" "F.Paste")
			(net "GND")
		)
		(pad "DA34" smd circle
			(at -8.919972 14.520926)
			(size 0.4318 0.4318)
			(layers "F.Cu" "F.Mask" "F.Paste")
			(net "GND")
		)
		(pad "DA36" smd circle
			(at -7.202932 14.520926)
			(size 0.4318 0.4318)
			(layers "F.Cu" "F.Mask" "F.Paste")
			(net "GND")
		)
		(pad "DA38" smd circle
			(at -5.485892 14.520926)
			(size 0.4318 0.4318)
			(layers "F.Cu" "F.Mask" "F.Paste")
			(net "GND")
		)
		(pad "DA40" smd circle
			(at -3.769106 14.520926)
			(size 0.4318 0.4318)
			(layers "F.Cu" "F.Mask" "F.Paste")
			(net "TP_CPU1_RSVD_51")
		)
		(pad "DA42" smd circle
			(at -2.052066 14.520926)
			(size 0.4318 0.4318)
			(layers "F.Cu" "F.Mask" "F.Paste")
			(net "M_M_DQ<36>")
		)
		(pad "DA44" smd circle
			(at 1.193546 12.720828)
			(size 0.508 0.508)
			(layers "F.Cu" "F.Mask" "F.Paste")
			(net "GND")
		)
		(pad "DA46" smd circle
			(at 2.910586 12.720828)
			(size 0.4318 0.4318)
			(layers "F.Cu" "F.Mask" "F.Paste")
			(net "GND")
		)
		(pad "DA48" smd circle
			(at 4.627626 12.720828)
			(size 0.4318 0.4318)
			(layers "F.Cu" "F.Mask" "F.Paste")
			(net "GND")
		)
	)
)
